# BASEBOARD_FAB2 (Tioga Pass) — schematic netlist excerpt (pin names and nets, part order shuffled) for the footprints in the layout excerpt that follows; sources: Cadence DE-HDL packaged netlist, KiCad conversion of Wiwynn_Tioga_Pass_MB.brd

RN8F6  82KR2F-1-GP  1%  pkg SMD-RG  page 246 : \1\ = TPM_SPI_BMC_WP_N ; \2\ = GND
C3N21  CAP_A  1.0UF 6.3V 10% X6S  pkg 0402V  page 130 : A = P1V8_PCH_STBY ; B = GND
R769  RES  0.0 5% CHIP  pkg 0402  page 244 : A = P3E_CPU0_PE1_PCH_RXP<14> ; B = P3E_CPU0_PE1_PCH_CON_RXP<14>

(kicad_pcb
	(version 20260206)
	(generator "pcbnew")
	(generator_version "10.0")
	(general
		(thickness 1.6)
		(legacy_teardrops no)
	)
	(paper "A4")
	(title_block
		(title "Wiwynn_Tioga_Pass_MB.brd")
		(comment 1 "Tioga Pass / footprints 4645-4647 of 4770")
	)
	(layers
		(0 "F.Cu" signal "TOP")
		(4 "In1.Cu" signal "L2GND")
		(6 "In2.Cu" signal "L3")
		(8 "In3.Cu" signal "L4GND")
		(10 "In4.Cu" signal "L5")
		(12 "In5.Cu" signal "L6GND")
		(14 "In6.Cu" signal "L7VCC")
		(16 "In7.Cu" signal "L8VCC")
		(18 "In8.Cu" signal "L9GND")
		(20 "In9.Cu" signal "L10")
		(22 "In10.Cu" signal "L11GND")
		(24 "In11.Cu" signal "L12")
		(26 "In12.Cu" signal "L13GND")
		(2 "B.Cu" signal "BOTTOM")
		(9 "F.Adhes" user "F.Adhesive")
		(11 "B.Adhes" user "B.Adhesive")
		(13 "F.Paste" user "Package Geometry/Pastemask Top")
		(15 "B.Paste" user "Package Geometry/Pastemask Bottom")
		(5 "F.SilkS" user "Ref Des/Silkscreen Top")
		(7 "B.SilkS" user "Ref Des/Silkscreen Bottom")
		(1 "F.Mask" user "Board Geometry/Soldermask Top")
		(3 "B.Mask" user "Board Geometry/Soldermask Bottom")
		(17 "Dwgs.User" user "User.Drawings")
		(19 "Cmts.User" user "User.Comments")
		(21 "Eco1.User" user "User.Eco1")
		(23 "Eco2.User" user "User.Eco2")
		(25 "Edge.Cuts" user "Board Geometry/Outline")
		(27 "Margin" user)
		(31 "F.CrtYd" user "Package Geometry/Place Bound Top")
		(29 "B.CrtYd" user "Package Geometry/Place Bound Bottom")
		(35 "F.Fab" user "Ref Des/Assembly Top")
		(33 "B.Fab" user "Ref Des/Assembly Bottom")
	)
	(footprint ""
		(layer "B.Cu")
		(at 388.239 -105.918 180)
		(property "Reference" "C3N21"
			(at 0 0 0)
			(layer "B.SilkS")
			(hide yes)
			(effects
				(font
					(size 1.27 1.27)
				)
				(justify mirror)
			)
		)
		(property "Value" ""
			(at 0 0 0)
			(layer "B.Fab")
			(effects
				(font
					(size 1.27 1.27)
				)
				(justify mirror)
			)
		)
		(duplicate_pad_numbers_are_jumpers no)
		(fp_poly
			(pts
				(xy -0.3048 -0.1016) (xy -0.3048 0.9906) (xy 0.3048 0.9906) (xy 0.3048 -0.1016)
			)
			(stroke
				(width 0)
				(type default)
			)
			(fill no)
			(layer "B.CrtYd")
		)
		(fp_line
			(start 0.3048 0.9906)
			(end -0.3048 0.9906)
			(stroke
				(width 0.1)
				(type default)
			)
			(layer "B.Fab")
		)
		(fp_line
			(start 0.3048 -0.1016)
			(end 0.3048 0.9906)
			(stroke
				(width 0.1)
				(type default)
			)
			(layer "B.Fab")
		)
		(fp_line
			(start -0.3048 0.9906)
			(end -0.3048 -0.1016)
			(stroke
				(width 0.1)
				(type default)
			)
			(layer "B.Fab")
		)
		(fp_line
			(start -0.3048 -0.1016)
			(end 0.3048 -0.1016)
			(stroke
				(width 0.1)
				(type default)
			)
			(layer "B.Fab")
		)
		(pad "1" smd rect
			(at 0 0)
			(size 0.508 0.508)
			(layers "B.Cu" "B.Mask" "B.Paste")
			(net "P1V8_PCH_STBY")
		)
		(pad "2" smd rect
			(at 0 0.889)
			(size 0.508 0.508)
			(layers "B.Cu" "B.Mask" "B.Paste")
			(net "GND")
		)
		(zone
			(layer "B.Cu")
			(hatch none 0.5)
			(connect_pads
				(clearance 0)
			)
			(min_thickness 0.25)
			(keepout
				(tracks not_allowed)
				(vias allowed)
				(pads allowed)
				(copperpour not_allowed)
				(footprints allowed)
			)
			(placement
				(enabled no)
				(sheetname "")
			)
			(fill
				(thermal_gap 0.5)
				(thermal_bridge_width 0.5)
				(island_removal_mode 0)
			)
			(polygon
				(pts
					(xy 387.985 -106.553) (xy 388.493 -106.553) (xy 388.493 -106.172) (xy 387.985 -106.172)
				)
			)
		)
		(zone
			(layer "B.Cu")
			(hatch none 0.5)
			(connect_pads
				(clearance 0)
			)
			(min_thickness 0.25)
			(keepout
				(tracks allowed)
				(vias not_allowed)
				(pads allowed)
				(copperpour not_allowed)
				(footprints allowed)
			)
			(placement
				(enabled no)
				(sheetname "")
			)
			(fill
				(thermal_gap 0.5)
				(thermal_bridge_width 0.5)
				(island_removal_mode 0)
			)
			(polygon
				(pts
					(xy 387.985 -106.172) (xy 388.493 -106.172) (xy 388.493 -106.553) (xy 387.985 -106.553)
				)
			)
		)
	)
	(footprint ""
		(layer "B.Cu")
		(at 349.133414 -126.345442 -90)
		(property "Reference" "R769"
			(at 0.8382 -0.67818 270)
			(unlocked yes)
			(layer "B.SilkS")
			(effects
				(font
					(size 0.4064 0.254)
					(thickness 0.1524)
				)
				(justify left mirror)
			)
		)
		(property "Value" ""
			(at 0 0 90)
			(layer "B.Fab")
			(effects
				(font
					(size 1.27 1.27)
				)
				(justify mirror)
			)
		)
		(duplicate_pad_numbers_are_jumpers no)
		(fp_poly
			(pts
				(xy 0.2794 -0.1016) (xy -0.2794 -0.1016) (xy -0.2794 0.9906) (xy 0.2794 0.9906)
			)
			(stroke
				(width 0)
				(type default)
			)
			(fill no)
			(layer "B.CrtYd")
		)
		(fp_line
			(start -0.2794 0.9906)
			(end -0.2794 -0.1016)
			(stroke
				(width 0.1)
				(type default)
			)
			(layer "B.Fab")
		)
		(fp_line
			(start 0.2794 0.9906)
			(end -0.2794 0.9906)
			(stroke
				(width 0.1)
				(type default)
			)
			(layer "B.Fab")
		)
		(fp_line
			(start -0.2794 -0.1016)
			(end 0.2794 -0.1016)
			(stroke
				(width 0.1)
				(type default)
			)
			(layer "B.Fab")
		)
		(fp_line
			(start 0.2794 -0.1016)
			(end 0.2794 0.9906)
			(stroke
				(width 0.1)
				(type default)
			)
			(layer "B.Fab")
		)
		(pad "1" smd rect
			(at 0 0 90)
			(size 0.508 0.508)
			(layers "B.Cu" "B.Mask" "B.Paste")
			(net "P3E_CPU0_PE1_PCH_RXP<14>")
		)
		(pad "2" smd rect
			(at 0 0.889 90)
			(size 0.508 0.508)
			(layers "B.Cu" "B.Mask" "B.Paste")
			(net "P3E_CPU0_PE1_PCH_CON_RXP<14>")
		)
		(zone
			(layer "B.Cu")
			(hatch none 0.5)
			(connect_pads
				(clearance 0)
			)
			(min_thickness 0.25)
			(keepout
				(tracks not_allowed)
				(vias allowed)
				(pads allowed)
				(copperpour not_allowed)
				(footprints allowed)
			)
			(placement
				(enabled no)
				(sheetname "")
			)
			(fill
				(thermal_gap 0.5)
				(thermal_bridge_width 0.5)
				(island_removal_mode 0)
			)
			(polygon
				(pts
					(xy 348.498414 -126.091442) (xy 348.498414 -126.599442) (xy 348.879414 -126.599442) (xy 348.879414 -126.091442)
				)
			)
		)
		(zone
			(layer "B.Cu")
			(hatch none 0.5)
			(connect_pads
				(clearance 0)
			)
			(min_thickness 0.25)
			(keepout
				(tracks allowed)
				(vias not_allowed)
				(pads allowed)
				(copperpour not_allowed)
				(footprints allowed)
			)
			(placement
				(enabled no)
				(sheetname "")
			)
			(fill
				(thermal_gap 0.5)
				(thermal_bridge_width 0.5)
				(island_removal_mode 0)
			)
			(polygon
				(pts
					(xy 348.879414 -126.091442) (xy 348.879414 -126.599442) (xy 348.498414 -126.599442) (xy 348.498414 -126.091442)
				)
			)
		)
	)
	(footprint ""
		(layer "B.Cu")
		(at 370.078 -26.162)
		(property "Reference" "RN8F6"
			(at 0 0 0)
			(layer "B.SilkS")
			(hide yes)
			(effects
				(font
					(size 1.27 1.27)
				)
				(justify mirror)
			)
		)
		(property "Value" "*"
			(at -0.064008 -4.108196 0)
			(unlocked yes)
			(layer "B.Fab")
			(hide yes)
			(effects
				(font
					(size 1.27 1.016)
					(thickness 0.1524)
				)
				(justify mirror)
			)
		)
		(property "Device Type" "82KR2F-1-GP_SMD-RG-82KR2F-1-GPA"
			(at -0.064008 -5.632196 0)
			(unlocked yes)
			(layer "B.Fab")
			(hide yes)
			(effects
				(font
					(size 1.27 1.016)
					(thickness 0.1524)
				)
				(justify mirror)
			)
		)
		(duplicate_pad_numbers_are_jumpers no)
		(fp_line
			(start -0.508 -0.9398)
			(end 0.508 -0.9398)
			(stroke
				(width 0.1524)
				(type default)
			)
			(layer "B.SilkS")
		)
		(fp_line
			(start 0.508 -0.9398)
			(end 0.508 0.9398)
			(stroke
				(width 0.1524)
				(type default)
			)
			(layer "B.SilkS")
		)
		(fp_rect
			(start 0.508 0.9398)
			(end -0.508 -0.9398)
			(stroke
				(width 0)
				(type default)
			)
			(fill no)
			(layer "B.CrtYd")
		)
		(fp_rect
			(start 0.508 0.9398)
			(end -0.508 -0.9398)
			(stroke
				(width 0)
				(type default)
			)
			(fill no)
			(layer "B.Fab")
		)
		(pad "1" smd custom
			(at 0 -0.4445 180)
			(size 0.1397 0.1397)
			(layers "B.Cu" "B.Mask" "B.Paste")
			(net "TPM_SPI_BMC_WP_N")
			(options
				(clearance outline)
				(anchor circle)
			)
			(primitives
				(gr_poly
					(pts
						(arc
							(start -0.1778 0.2794)
							(mid -0.249642 0.249642)
							(end -0.2794 0.1778)
						)
						(arc
							(start -0.2794 -0.1778)
							(mid -0.249642 -0.249642)
							(end -0.1778 -0.2794)
						)
						(arc
							(start 0.1778 -0.2794)
							(mid 0.249642 -0.249642)
							(end 0.2794 -0.1778)
						)
						(arc
							(start 0.2794 0.1778)
							(mid 0.249642 0.249642)
							(end 0.1778 0.2794)
						)
					)
					(width 0)
					(fill yes)
				)
			)
		)
		(pad "2" smd custom
			(at 0 0.4445 180)
			(size 0.1397 0.1397)
			(layers "B.Cu" "B.Mask" "B.Paste")
			(net "GND")
			(options
				(clearance outline)
				(anchor circle)
			)
			(primitives
				(gr_poly
					(pts
						(arc
							(start -0.1778 0.2794)
							(mid -0.249642 0.249642)
							(end -0.2794 0.1778)
						)
						(arc
							(start -0.2794 -0.1778)
							(mid -0.249642 -0.249642)
							(end -0.1778 -0.2794)
						)
						(arc
							(start 0.1778 -0.2794)
							(mid 0.249642 -0.249642)
							(end 0.2794 -0.1778)
						)
						(arc
							(start 0.2794 0.1778)
							(mid 0.249642 0.249642)
							(end 0.1778 0.2794)
						)
					)
					(width 0)
					(fill yes)
				)
			)
		)
	)
)
